FILE_TYPE = CONNECTIVITY;
{Allegro Design Entry HDL 16.6-p007 (v16-6-112F) 10/10/2012}
"PAGE_NUMBER" = 26;
0"NC";
1"M_D_DQS_DP<17:0>";
2"M_D_DQS_DN<17:0>";
3"M_D_MA<17:0>";
4"M_D_BA<1:0>";
5"M_D_BG<1:0>";
6"M_D_CKE<3:0>";
7"M_D_CS_N<7:0>";
8"M_D_ODT<3:0>";
9"M_D_DQ<63:0>";
10"M_D_CLK_DN<3:0>";
11"M_D_CLK_DP<3:0>";
12"M_D_ECC<7:0>";
13"M_D_DQ<5>";
14"M_D_C<2>";
15"M_D_ECC<0>";
16"M_D_ECC<1>";
17"M_D_ECC<2>";
18"M_D_ECC<3>";
19"M_D_ECC<4>";
20"M_D_ECC<5>";
21"M_D_ECC<6>";
22"M_D_ECC<7>";
23"M_D_DQ<0>";
24"M_D_DQ<1>";
25"M_D_DQ<2>";
26"M_D_DQ<3>";
27"M_D_DQ<4>";
28"M_D_DQ<6>";
29"M_D_DQ<7>";
30"M_D_DQ<8>";
31"M_D_DQ<9>";
32"M_D_DQ<10>";
33"M_D_CLK_DP<0>";
34"M_D_CLK_DP<1>";
35"M_D_CLK_DP<2>";
36"M_D_CLK_DP<3>";
37"M_D_CLK_DN<0>";
38"M_D_CLK_DN<1>";
39"M_D_CLK_DN<2>";
40"M_D_CLK_DN<3>";
41"M_D_DQ<11>";
42"M_D_DQ<12>";
43"M_D_DQ<13>";
44"M_D_DQ<14>";
45"M_D_DQ<15>";
46"M_D_DQ<16>";
47"M_D_DQ<17>";
48"M_D_DQ<18>";
49"M_D_DQ<19>";
50"M_D_DQ<20>";
51"M_D_DQ<21>";
52"M_D_DQ<22>";
53"M_D_DQ<23>";
54"M_D_DQ<24>";
55"M_D_DQ<25>";
56"M_D_DQ<26>";
57"M_D_DQ<27>";
58"M_D_DQ<28>";
59"M_D_DQ<29>";
60"M_D_DQ<30>";
61"M_D_DQ<31>";
62"M_D_DQ<32>";
63"M_D_DQ<33>";
64"M_D_DQ<34>";
65"M_D_DQ<35>";
66"M_D_DQ<36>";
67"M_D_DQ<37>";
68"M_D_DQ<38>";
69"M_D_DQ<39>";
70"M_D_DQ<40>";
71"M_D_DQ<41>";
72"M_D_DQ<42>";
73"M_D_DQ<43>";
74"M_D_DQ<44>";
75"M_D_DQ<45>";
76"M_D_DQ<46>";
77"M_D_DQ<47>";
78"M_D_DQ<48>";
79"M_D_DQ<49>";
80"M_D_DQ<50>";
81"M_D_DQ<51>";
82"M_D_DQ<52>";
83"M_D_DQ<53>";
84"M_D_DQ<54>";
85"M_D_DQ<55>";
86"M_D_DQ<56>";
87"M_D_DQ<57>";
88"M_D_DQ<58>";
89"M_D_DQ<59>";
90"M_D_DQ<60>";
91"M_D_DQ<61>";
92"M_D_DQ<62>";
93"M_D_DQ<63>";
94"M_D_ODT<0>";
95"M_D_ODT<1>";
96"M_D_ODT<2>";
97"M_D_ODT<3>";
98"M_D_MA<0>";
99"M_D_MA<1>";
100"M_D_MA<2>";
101"M_D_CS_N<0>";
102"M_D_CS_N<1>";
103"M_D_CS_N<2>";
104"M_D_CS_N<3>";
105"M_D_CS_N<4>";
106"M_D_CS_N<5>";
107"M_D_CS_N<6>";
108"M_D_CS_N<7>";
109"M_D_CKE<0>";
110"M_D_CKE<1>";
111"M_D_CKE<2>";
112"M_D_CKE<3>";
113"M_D_BG<0>";
114"M_D_BG<1>";
115"M_D_BA<0>";
116"M_D_BA<1>";
117"M_D_MA<3>";
118"M_D_MA<4>";
119"M_D_MA<5>";
120"M_D_MA<6>";
121"M_D_MA<7>";
122"M_D_MA<8>";
123"M_D_MA<9>";
124"M_D_MA<10>";
125"M_D_MA<11>";
126"M_D_MA<12>";
127"M_D_MA<13>";
128"M_D_MA<14>";
129"M_D_MA<15>";
130"M_D_MA<16>";
131"M_D_MA<17>";
132"M_D_DQS_DP<0>";
133"M_D_DQS_DP<1>";
134"M_D_DQS_DP<2>";
135"M_D_DQS_DP<3>";
136"M_D_DQS_DP<4>";
137"M_D_DQS_DP<5>";
138"M_D_DQS_DN<0>";
139"M_D_DQS_DN<1>";
140"M_D_DQS_DN<2>";
141"M_D_DQS_DN<3>";
142"M_D_DQS_DN<4>";
143"M_D_DQS_DN<5>";
144"M_D_DQS_DN<6>";
145"M_D_DQS_DN<7>";
146"M_D_DQS_DN<8>";
147"M_D_DQS_DN<9>";
148"M_D_DQS_DN<10>";
149"M_D_DQS_DN<11>";
150"M_D_DQS_DN<12>";
151"M_D_DQS_DN<13>";
152"M_D_DQS_DN<14>";
153"M_D_DQS_DN<15>";
154"M_D_DQS_DN<16>";
155"M_D_DQS_DN<17>";
156"M_D_PAR";
157"M_D_ALERT_N";
158"M_D_ACT_N";
159"M_D_DQS_DP<6>";
160"M_D_DQS_DP<7>";
161"M_D_DQS_DP<8>";
162"M_D_DQS_DP<9>";
163"M_D_DQS_DP<10>";
164"M_D_DQS_DP<11>";
165"M_D_DQS_DP<12>";
166"M_D_DQS_DP<13>";
167"M_D_DQS_DP<14>";
168"M_D_DQS_DP<15>";
169"M_D_DQS_DP<16>";
170"M_D_DQS_DP<17>";
%"TAP"
"6","(-5500,875)","0","mstr_standard","I10";
;
HDL_TAP"TRUE"
BODY_TYPE"PLUMBING"
CDS_LIB"mstr_standard";
"B \NAC \NWC"11;
"S \NAC"
BN"1"34;
%"TAP"
"6","(-2775,1525)","2","mstr_standard","I100";
;
HDL_TAP"TRUE"
BODY_TYPE"PLUMBING"
CDS_LIB"mstr_standard";
"B \NAC \NWC"8;
"S \NAC"
BN"2"96;
%"TAP"
"6","(-2775,1575)","2","mstr_standard","I101";
;
HDL_TAP"TRUE"
BODY_TYPE"PLUMBING"
CDS_LIB"mstr_standard";
"B \NAC \NWC"8;
"S \NAC"
BN"3"97;
%"TAP"
"6","(-2775,1475)","2","mstr_standard","I102";
;
HDL_TAP"TRUE"
BODY_TYPE"PLUMBING"
CDS_LIB"mstr_standard";
"B \NAC \NWC"8;
"S \NAC"
BN"1"95;
%"TAP"
"6","(-2775,1675)","2","mstr_standard","I103";
;
HDL_TAP"TRUE"
BODY_TYPE"PLUMBING"
CDS_LIB"mstr_standard";
"B \NAC \NWC"6;
"S \NAC"
BN"0"109;
%"TAP"
"6","(-2775,1725)","2","mstr_standard","I104";
;
HDL_TAP"TRUE"
BODY_TYPE"PLUMBING"
CDS_LIB"mstr_standard";
"B \NAC \NWC"6;
"S \NAC"
BN"1"110;
%"TAP"
"6","(-2775,1775)","2","mstr_standard","I105";
;
HDL_TAP"TRUE"
BODY_TYPE"PLUMBING"
CDS_LIB"mstr_standard";
"B \NAC \NWC"6;
"S \NAC"
BN"2"111;
%"TAP"
"6","(-2775,1825)","2","mstr_standard","I106";
;
HDL_TAP"TRUE"
BODY_TYPE"PLUMBING"
CDS_LIB"mstr_standard";
"B \NAC \NWC"6;
"S \NAC"
BN"3"112;
%"TAP"
"6","(-2775,1925)","2","mstr_standard","I107";
;
HDL_TAP"TRUE"
BODY_TYPE"PLUMBING"
CDS_LIB"mstr_standard";
"B \NAC \NWC"3;
"S \NAC"
BN"0"98;
%"TAP"
"6","(-2775,1975)","2","mstr_standard","I108";
;
HDL_TAP"TRUE"
BODY_TYPE"PLUMBING"
CDS_LIB"mstr_standard";
"B \NAC \NWC"3;
"S \NAC"
BN"1"99;
%"TAP"
"6","(-2775,2075)","2","mstr_standard","I109";
;
HDL_TAP"TRUE"
BODY_TYPE"PLUMBING"
CDS_LIB"mstr_standard";
"B \NAC \NWC"3;
"S \NAC"
BN"3"117;
%"TAP"
"6","(-5500,925)","0","mstr_standard","I11";
;
HDL_TAP"TRUE"
BODY_TYPE"PLUMBING"
CDS_LIB"mstr_standard";
"B \NAC \NWC"11;
"S \NAC"
BN"2"35;
%"TAP"
"6","(-2775,2025)","2","mstr_standard","I110";
;
HDL_TAP"TRUE"
BODY_TYPE"PLUMBING"
CDS_LIB"mstr_standard";
"B \NAC \NWC"3;
"S \NAC"
BN"2"100;
%"TAP"
"6","(-2775,2125)","2","mstr_standard","I111";
;
HDL_TAP"TRUE"
BODY_TYPE"PLUMBING"
CDS_LIB"mstr_standard";
"B \NAC \NWC"3;
"S \NAC"
BN"4"118;
%"TAP"
"6","(-2775,2225)","2","mstr_standard","I112";
;
HDL_TAP"TRUE"
BODY_TYPE"PLUMBING"
CDS_LIB"mstr_standard";
"B \NAC \NWC"3;
"S \NAC"
BN"6"120;
%"TAP"
"6","(-2775,2175)","2","mstr_standard","I113";
;
HDL_TAP"TRUE"
BODY_TYPE"PLUMBING"
CDS_LIB"mstr_standard";
"B \NAC \NWC"3;
"S \NAC"
BN"5"119;
%"TAP"
"6","(-2775,2275)","2","mstr_standard","I114";
;
HDL_TAP"TRUE"
BODY_TYPE"PLUMBING"
CDS_LIB"mstr_standard";
"B \NAC \NWC"3;
"S \NAC"
BN"7"121;
%"TAP"
"6","(-2775,2325)","2","mstr_standard","I115";
;
HDL_TAP"TRUE"
BODY_TYPE"PLUMBING"
CDS_LIB"mstr_standard";
"B \NAC \NWC"3;
"S \NAC"
BN"8"122;
%"TAP"
"6","(-2775,2375)","2","mstr_standard","I116";
;
HDL_TAP"TRUE"
BODY_TYPE"PLUMBING"
CDS_LIB"mstr_standard";
"B \NAC \NWC"3;
"S \NAC"
BN"9"123;
%"TAP"
"6","(-2775,2425)","2","mstr_standard","I117";
;
HDL_TAP"TRUE"
BODY_TYPE"PLUMBING"
CDS_LIB"mstr_standard";
"B \NAC \NWC"3;
"S \NAC"
BN"10"124;
%"TAP"
"6","(-2775,2475)","2","mstr_standard","I118";
;
HDL_TAP"TRUE"
BODY_TYPE"PLUMBING"
CDS_LIB"mstr_standard";
"B \NAC \NWC"3;
"S \NAC"
BN"11"125;
%"TAP"
"6","(-2775,2575)","2","mstr_standard","I119";
;
HDL_TAP"TRUE"
BODY_TYPE"PLUMBING"
CDS_LIB"mstr_standard";
"B \NAC \NWC"3;
"S \NAC"
BN"13"127;
%"TAP"
"6","(-5500,975)","0","mstr_standard","I12";
;
HDL_TAP"TRUE"
BODY_TYPE"PLUMBING"
CDS_LIB"mstr_standard";
"B \NAC \NWC"11;
"S \NAC"
BN"3"36;
%"TAP"
"6","(-2775,2525)","2","mstr_standard","I120";
;
HDL_TAP"TRUE"
BODY_TYPE"PLUMBING"
CDS_LIB"mstr_standard";
"B \NAC \NWC"3;
"S \NAC"
BN"12"126;
%"TAP"
"6","(-2775,2675)","2","mstr_standard","I121";
;
HDL_TAP"TRUE"
BODY_TYPE"PLUMBING"
CDS_LIB"mstr_standard";
"B \NAC \NWC"3;
"S \NAC"
BN"15"129;
%"TAP"
"6","(-2775,2725)","2","mstr_standard","I122";
;
HDL_TAP"TRUE"
BODY_TYPE"PLUMBING"
CDS_LIB"mstr_standard";
"B \NAC \NWC"3;
"S \NAC"
BN"16"130;
%"TAP"
"6","(-2775,2625)","2","mstr_standard","I123";
;
HDL_TAP"TRUE"
BODY_TYPE"PLUMBING"
CDS_LIB"mstr_standard";
"B \NAC \NWC"3;
"S \NAC"
BN"14"128;
%"TAP"
"6","(-2775,2775)","2","mstr_standard","I124";
;
HDL_TAP"TRUE"
BODY_TYPE"PLUMBING"
CDS_LIB"mstr_standard";
"B \NAC \NWC"3;
"S \NAC"
BN"17"131;
%"TAP"
"6","(-2775,2925)","2","mstr_standard","I125";
;
HDL_TAP"TRUE"
BODY_TYPE"PLUMBING"
CDS_LIB"mstr_standard";
"B \NAC \NWC"2;
"S \NAC"
BN"1"139;
%"TAP"
"6","(-2775,2975)","2","mstr_standard","I126";
;
HDL_TAP"TRUE"
BODY_TYPE"PLUMBING"
CDS_LIB"mstr_standard";
"B \NAC \NWC"2;
"S \NAC"
BN"2"140;
%"TAP"
"6","(-2775,2875)","2","mstr_standard","I127";
;
HDL_TAP"TRUE"
BODY_TYPE"PLUMBING"
CDS_LIB"mstr_standard";
"B \NAC \NWC"2;
"S \NAC"
BN"0"138;
%"TAP"
"6","(-2775,3025)","2","mstr_standard","I128";
;
HDL_TAP"TRUE"
BODY_TYPE"PLUMBING"
CDS_LIB"mstr_standard";
"B \NAC \NWC"2;
"S \NAC"
BN"3"141;
%"TAP"
"6","(-2775,3075)","2","mstr_standard","I129";
;
HDL_TAP"TRUE"
BODY_TYPE"PLUMBING"
CDS_LIB"mstr_standard";
"B \NAC \NWC"2;
"S \NAC"
BN"4"142;
%"TAP"
"6","(-5500,1075)","0","mstr_standard","I13";
;
HDL_TAP"TRUE"
BODY_TYPE"PLUMBING"
CDS_LIB"mstr_standard";
"B \NAC \NWC"12;
"S \NAC"
BN"0"15;
%"TAP"
"6","(-2775,3125)","2","mstr_standard","I130";
;
HDL_TAP"TRUE"
BODY_TYPE"PLUMBING"
CDS_LIB"mstr_standard";
"B \NAC \NWC"2;
"S \NAC"
BN"5"143;
%"TAP"
"6","(-2775,3175)","2","mstr_standard","I131";
;
HDL_TAP"TRUE"
BODY_TYPE"PLUMBING"
CDS_LIB"mstr_standard";
"B \NAC \NWC"2;
"S \NAC"
BN"6"144;
%"TAP"
"6","(-2775,3225)","2","mstr_standard","I132";
;
HDL_TAP"TRUE"
BODY_TYPE"PLUMBING"
CDS_LIB"mstr_standard";
"B \NAC \NWC"2;
"S \NAC"
BN"7"145;
%"TAP"
"6","(-2775,3275)","2","mstr_standard","I133";
;
HDL_TAP"TRUE"
BODY_TYPE"PLUMBING"
CDS_LIB"mstr_standard";
"B \NAC \NWC"2;
"S \NAC"
BN"8"146;
%"TAP"
"6","(-2775,3325)","2","mstr_standard","I134";
;
HDL_TAP"TRUE"
BODY_TYPE"PLUMBING"
CDS_LIB"mstr_standard";
"B \NAC \NWC"2;
"S \NAC"
BN"9"147;
%"TAP"
"6","(-2775,3375)","2","mstr_standard","I135";
;
HDL_TAP"TRUE"
BODY_TYPE"PLUMBING"
CDS_LIB"mstr_standard";
"B \NAC \NWC"2;
"S \NAC"
BN"10"148;
%"TAP"
"6","(-2775,3475)","2","mstr_standard","I136";
;
HDL_TAP"TRUE"
BODY_TYPE"PLUMBING"
CDS_LIB"mstr_standard";
"B \NAC \NWC"2;
"S \NAC"
BN"12"150;
%"TAP"
"6","(-2775,3425)","2","mstr_standard","I137";
;
HDL_TAP"TRUE"
BODY_TYPE"PLUMBING"
CDS_LIB"mstr_standard";
"B \NAC \NWC"2;
"S \NAC"
BN"11"149;
%"TAP"
"6","(-2775,3575)","2","mstr_standard","I138";
;
HDL_TAP"TRUE"
BODY_TYPE"PLUMBING"
CDS_LIB"mstr_standard";
"B \NAC \NWC"2;
"S \NAC"
BN"14"152;
%"TAP"
"6","(-2775,3625)","2","mstr_standard","I139";
;
HDL_TAP"TRUE"
BODY_TYPE"PLUMBING"
CDS_LIB"mstr_standard";
"B \NAC \NWC"2;
"S \NAC"
BN"15"153;
%"TAP"
"6","(-5500,1125)","0","mstr_standard","I14";
;
HDL_TAP"TRUE"
BODY_TYPE"PLUMBING"
CDS_LIB"mstr_standard";
"B \NAC \NWC"12;
"S \NAC"
BN"1"16;
%"TAP"
"6","(-2775,3525)","2","mstr_standard","I140";
;
HDL_TAP"TRUE"
BODY_TYPE"PLUMBING"
CDS_LIB"mstr_standard";
"B \NAC \NWC"2;
"S \NAC"
BN"13"151;
%"TAP"
"6","(-2775,3725)","2","mstr_standard","I141";
;
HDL_TAP"TRUE"
BODY_TYPE"PLUMBING"
CDS_LIB"mstr_standard";
"B \NAC \NWC"2;
"S \NAC"
BN"17"155;
%"TAP"
"6","(-2775,3675)","2","mstr_standard","I142";
;
HDL_TAP"TRUE"
BODY_TYPE"PLUMBING"
CDS_LIB"mstr_standard";
"B \NAC \NWC"2;
"S \NAC"
BN"16"154;
%"TAP"
"6","(-2775,3875)","2","mstr_standard","I143";
;
HDL_TAP"TRUE"
BODY_TYPE"PLUMBING"
CDS_LIB"mstr_standard";
"B \NAC \NWC"1;
"S \NAC"
BN"1"133;
%"TAP"
"6","(-2775,3825)","2","mstr_standard","I144";
;
HDL_TAP"TRUE"
BODY_TYPE"PLUMBING"
CDS_LIB"mstr_standard";
"B \NAC \NWC"1;
"S \NAC"
BN"0"132;
%"TAP"
"6","(-2775,3925)","2","mstr_standard","I145";
;
HDL_TAP"TRUE"
BODY_TYPE"PLUMBING"
CDS_LIB"mstr_standard";
"B \NAC \NWC"1;
"S \NAC"
BN"2"134;
%"TAP"
"6","(-2775,3975)","2","mstr_standard","I146";
;
HDL_TAP"TRUE"
BODY_TYPE"PLUMBING"
CDS_LIB"mstr_standard";
"B \NAC \NWC"1;
"S \NAC"
BN"3"135;
%"TAP"
"6","(-5500,1175)","0","mstr_standard","I15";
;
HDL_TAP"TRUE"
BODY_TYPE"PLUMBING"
CDS_LIB"mstr_standard";
"B \NAC \NWC"12;
"S \NAC"
BN"2"17;
%"TAP"
"6","(-2775,4025)","2","mstr_standard","I157";
;
HDL_TAP"TRUE"
BODY_TYPE"PLUMBING"
CDS_LIB"mstr_standard";
"B \NAC \NWC"1;
"S \NAC"
BN"4"136;
%"TAP"
"6","(-2775,4125)","2","mstr_standard","I158";
;
HDL_TAP"TRUE"
BODY_TYPE"PLUMBING"
CDS_LIB"mstr_standard";
"B \NAC \NWC"1;
"S \NAC"
BN"6"159;
%"TAP"
"6","(-2775,4075)","2","mstr_standard","I159";
;
HDL_TAP"TRUE"
BODY_TYPE"PLUMBING"
CDS_LIB"mstr_standard";
"B \NAC \NWC"1;
"S \NAC"
BN"5"137;
%"TAP"
"6","(-5500,1275)","0","mstr_standard","I16";
;
HDL_TAP"TRUE"
BODY_TYPE"PLUMBING"
CDS_LIB"mstr_standard";
"B \NAC \NWC"12;
"S \NAC"
BN"4"19;
%"TAP"
"6","(-2775,4175)","2","mstr_standard","I160";
;
HDL_TAP"TRUE"
BODY_TYPE"PLUMBING"
CDS_LIB"mstr_standard";
"B \NAC \NWC"1;
"S \NAC"
BN"7"160;
%"TAP"
"6","(-2775,4275)","2","mstr_standard","I161";
;
HDL_TAP"TRUE"
BODY_TYPE"PLUMBING"
CDS_LIB"mstr_standard";
"B \NAC \NWC"1;
"S \NAC"
BN"9"162;
%"TAP"
"6","(-2775,4225)","2","mstr_standard","I162";
;
HDL_TAP"TRUE"
BODY_TYPE"PLUMBING"
CDS_LIB"mstr_standard";
"B \NAC \NWC"1;
"S \NAC"
BN"8"161;
%"TAP"
"6","(-2775,4325)","2","mstr_standard","I163";
;
HDL_TAP"TRUE"
BODY_TYPE"PLUMBING"
CDS_LIB"mstr_standard";
"B \NAC \NWC"1;
"S \NAC"
BN"10"163;
%"TAP"
"6","(-2775,4375)","2","mstr_standard","I164";
;
HDL_TAP"TRUE"
BODY_TYPE"PLUMBING"
CDS_LIB"mstr_standard";
"B \NAC \NWC"1;
"S \NAC"
BN"11"164;
%"TAP"
"6","(-2775,4425)","2","mstr_standard","I165";
;
HDL_TAP"TRUE"
BODY_TYPE"PLUMBING"
CDS_LIB"mstr_standard";
"B \NAC \NWC"1;
"S \NAC"
BN"12"165;
%"TAP"
"6","(-2775,4525)","2","mstr_standard","I166";
;
HDL_TAP"TRUE"
BODY_TYPE"PLUMBING"
CDS_LIB"mstr_standard";
"B \NAC \NWC"1;
"S \NAC"
BN"14"167;
%"TAP"
"6","(-2775,4475)","2","mstr_standard","I167";
;
HDL_TAP"TRUE"
BODY_TYPE"PLUMBING"
CDS_LIB"mstr_standard";
"B \NAC \NWC"1;
"S \NAC"
BN"13"166;
%"TAP"
"6","(-2775,4625)","2","mstr_standard","I168";
;
HDL_TAP"TRUE"
BODY_TYPE"PLUMBING"
CDS_LIB"mstr_standard";
"B \NAC \NWC"1;
"S \NAC"
BN"16"169;
%"TAP"
"6","(-2775,4575)","2","mstr_standard","I169";
;
HDL_TAP"TRUE"
BODY_TYPE"PLUMBING"
CDS_LIB"mstr_standard";
"B \NAC \NWC"1;
"S \NAC"
BN"15"168;
%"TAP"
"6","(-5500,1225)","0","mstr_standard","I17";
;
HDL_TAP"TRUE"
BODY_TYPE"PLUMBING"
CDS_LIB"mstr_standard";
"B \NAC \NWC"12;
"S \NAC"
BN"3"18;
%"TAP"
"6","(-2775,4675)","2","mstr_standard","I170";
;
HDL_TAP"TRUE"
BODY_TYPE"PLUMBING"
CDS_LIB"mstr_standard";
"B \NAC \NWC"1;
"S \NAC"
BN"17"170;
%"SKX_EXT_B"
"6","(-4100,2575)","0","chpset_lib","I172";
;
CDS_SEC"6"
ROOM"CPU0"
CDS_LOCATION"U5D1"
SEC"6"
SEC_TYPE"BGA1"
CDS_LIB"chpset_lib"
PACK_TYPE"BGA1"
MATERIAL"IC"
PART_NUMBER"TBD"
LOCATION"U5D1";
"DDR3_PAR"
$PN"ED53"156;
"DDR3_ODT<0>"
$PN"EE50"94;
"DDR3_ODT<1>"
$PN"EE48"95;
"DDR3_ODT<2>"
$PN"EA50"96;
"DDR3_ODT<3>"
$PN"EA48"97;
"DDR3_MA<0>"
$PN"EB53"98;
"DDR3_MA<1>"
$PN"ED57"99;
"DDR3_MA<2>"
$PN"EE58"100;
"DDR3_MA<3>"
$PN"EB57"117;
"DDR3_MA<4>"
$PN"ED59"118;
"DDR3_MA<5>"
$PN"EA58"119;
"DDR3_MA<6>"
$PN"EE60"120;
"DDR3_MA<7>"
$PN"EA60"121;
"DDR3_MA<8>"
$PN"EB59"122;
"DDR3_MA<9>"
$PN"EF61"123;
"DDR3_MA<10>"
$PN"DW54"124;
"DDR3_MA<11>"
$PN"EB61"125;
"DDR3_MA<12>"
$PN"DT63"126;
"DDR3_MA<13>"
$PN"DW48"127;
"DDR3_MA<14>"
$PN"ED51"128;
"DDR3_MA<15>"
$PN"DV49"129;
"DDR3_MA<16>"
$PN"EA52"130;
"DDR3_MA<17>"
$PN"EA46"131;
"DDR3_ECC<0>"
$PN"DA68"15;
"DDR3_ECC<1>"
$PN"DE68"16;
"DDR3_ECC<2>"
$PN"DB65"17;
"DDR3_ECC<3>"
$PN"DD65"18;
"DDR3_ECC<4>"
$PN"DB69"19;
"DDR3_ECC<5>"
$PN"DD69"20;
"DDR3_ECC<6>"
$PN"DA66"21;
"DDR3_ECC<7>"
$PN"DE66"22;
"DDR3_DQS_DP<0>"
$PN"CV85"132;
"DDR3_DQS_DP<1>"
$PN"DP85"133;
"DDR3_DQS_DP<2>"
$PN"DM81"134;
"DDR3_DQS_DP<3>"
$PN"DT75"135;
"DDR3_DQS_DP<4>"
$PN"EC38"136;
"DDR3_DQS_DP<5>"
$PN"DT35"137;
"DDR3_DQS_DP<6>"
$PN"DT29"159;
"DDR3_DQS_DP<7>"
$PN"DT23"160;
"DDR3_DQS_DP<8>"
$PN"DD67"161;
"DDR3_DQS_DP<9>"
$PN"CP85"162;
"DDR3_DQS_DP<10>"
$PN"DL84"163;
"DDR3_DQS_DP<11>"
$PN"DP79"164;
"DDR3_DQS_DP<12>"
$PN"DM75"165;
"DDR3_DQS_DP<13>"
$PN"DW38"166;
"DDR3_DQS_DP<14>"
$PN"DM35"167;
"DDR3_DQS_DP<15>"
$PN"DP29"168;
"DDR3_DQS_DP<16>"
$PN"DP23"169;
"DDR3_DQS_DP<17>"
$PN"CY67"170;
"DDR3_DQS_DN<0>"
$PN"CU84"138;
"DDR3_DQS_DN<1>"
$PN"DN84"139;
"DDR3_DQS_DN<2>"
$PN"DL82"140;
"DDR3_DQS_DN<3>"
$PN"DV75"141;
"DDR3_DQS_DN<4>"
$PN"EE38"142;
"DDR3_DQS_DN<5>"
$PN"DV35"143;
"DDR3_DQS_DN<6>"
$PN"DV29"144;
"DDR3_DQS_DN<7>"
$PN"DV23"145;
"DDR3_DQS_DN<8>"
$PN"DF67"146;
"DDR3_DQS_DN<9>"
$PN"CR84"147;
"DDR3_DQS_DN<10>"
$PN"DM85"148;
"DDR3_DQS_DN<11>"
$PN"DN80"149;
"DDR3_DQS_DN<12>"
$PN"DP75"150;
"DDR3_DQS_DN<13>"
$PN"EA38"151;
"DDR3_DQS_DN<14>"
$PN"DP35"152;
"DDR3_DQS_DN<15>"
$PN"DM29"153;
"DDR3_DQS_DN<16>"
$PN"DM23"154;
"DDR3_DQS_DN<17>"
$PN"DB67"155;
"DDR3_DQ<0>"
$PN"CN84"23;
"DDR3_DQ<1>"
$PN"CN86"24;
"DDR3_DQ<2>"
$PN"DA86"25;
"DDR3_DQ<3>"
$PN"DA84"26;
"DDR3_DQ<4>"
$PN"CL84"27;
"DDR3_DQ<5>"
$PN"CL86"13;
"DDR3_DQ<6>"
$PN"CW86"28;
"DDR3_DQ<7>"
$PN"CW84"29;
"DDR3_DQ<8>"
$PN"DG84"30;
"DDR3_DQ<9>"
$PN"DH85"31;
"DDR3_DQ<10>"
$PN"DV83"32;
"DDR3_DQ<11>"
$PN"DY83"41;
"DDR3_DQ<12>"
$PN"DD85"42;
"DDR3_DQ<13>"
$PN"DE84"43;
"DDR3_DQ<14>"
$PN"DR84"44;
"DDR3_DQ<15>"
$PN"DV85"45;
"DDR3_DQ<16>"
$PN"DM79"46;
"DDR3_DQ<17>"
$PN"DK81"47;
"DDR3_DQ<18>"
$PN"DT81"48;
"DDR3_DQ<19>"
$PN"DR82"49;
"DDR3_DQ<20>"
$PN"DK79"50;
"DDR3_DQ<21>"
$PN"DJ80"51;
"DDR3_DQ<22>"
$PN"DR80"52;
"DDR3_DQ<23>"
$PN"DN82"53;
"DDR3_DQ<24>"
$PN"DN76"54;
"DDR3_DQ<25>"
$PN"DU76"55;
"DDR3_DQ<26>"
$PN"DP73"56;
"DDR3_DQ<27>"
$PN"DT73"57;
"DDR3_DQ<28>"
$PN"DP77"58;
"DDR3_DQ<29>"
$PN"DT77"59;
"DDR3_DQ<30>"
$PN"DN74"60;
"DDR3_DQ<31>"
$PN"DU74"61;
"DDR3_DQ<32>"
$PN"EC40"62;
"DDR3_DQ<33>"
$PN"ED39"63;
"DDR3_DQ<34>"
$PN"EA36"64;
"DDR3_DQ<35>"
$PN"EC36"65;
"DDR3_DQ<36>"
$PN"DY39"66;
"DDR3_DQ<37>"
$PN"EA40"67;
"DDR3_DQ<38>"
$PN"DY37"68;
"DDR3_DQ<39>"
$PN"ED37"69;
"DDR3_DQ<40>"
$PN"DN36"70;
"DDR3_DQ<41>"
$PN"DU36"71;
"DDR3_DQ<42>"
$PN"DP33"72;
"DDR3_DQ<43>"
$PN"DT33"73;
"DDR3_DQ<44>"
$PN"DP37"74;
"DDR3_DQ<45>"
$PN"DT37"75;
"DDR3_DQ<46>"
$PN"DN34"76;
"DDR3_DQ<47>"
$PN"DU34"77;
"DDR3_DQ<48>"
$PN"DN30"78;
"DDR3_DQ<49>"
$PN"DU30"79;
"DDR3_DQ<50>"
$PN"DP27"80;
"DDR3_DQ<51>"
$PN"DT27"81;
"DDR3_DQ<52>"
$PN"DP31"82;
"DDR3_DQ<53>"
$PN"DT31"83;
"DDR3_DQ<54>"
$PN"DN28"84;
"DDR3_DQ<55>"
$PN"DU28"85;
"DDR3_DQ<56>"
$PN"DN24"86;
"DDR3_DQ<57>"
$PN"DU24"87;
"DDR3_DQ<58>"
$PN"DY21"88;
"DDR3_DQ<59>"
$PN"EB21"89;
"DDR3_DQ<60>"
$PN"DP25"90;
"DDR3_DQ<61>"
$PN"DT25"91;
"DDR3_DQ<62>"
$PN"EC22"92;
"DDR3_DQ<63>"
$PN"DW22"93;
"DDR3_CS_N<0>"
$PN"EF51"101;
"DDR3_CS_N<1>"
$PN"ED49"102;
"DDR3_CS_N<2>"
$PN"ED47"103;
"DDR3_CS_N<3>"
$PN"EB47"104;
"DDR3_CS_N<4>"
$PN"EB51"105;
"DDR3_CS_N<5>"
$PN"EB49"106;
"DDR3_CS_N<6>"
$PN"DV45"107;
"DDR3_CS_N<7>"
$PN"EB45"108;
"DDR3_CLK_DP<0>"
$PN"EB55"33;
"DDR3_CLK_DP<1>"
$PN"EE54"34;
"DDR3_CLK_DP<2>"
$PN"EA56"35;
"DDR3_CLK_DP<3>"
$PN"EE56"36;
"DDR3_CLK_DN<0>"
$PN"ED55"37;
"DDR3_CLK_DN<1>"
$PN"EF55"38;
"DDR3_CLK_DN<2>"
$PN"DW56"39;
"DDR3_CLK_DN<3>"
$PN"EF57"40;
"DDR3_CKE<0>"
$PN"EE62"109;
"DDR3_CKE<1>"
$PN"EF63"110;
"DDR3_CKE<2>"
$PN"EA62"111;
"DDR3_CKE<3>"
$PN"EB63"112;
"DDR3_CID<2>"
$PN"DV47"14;
"DDR3_BG<0>"
$PN"ED61"113;
"DDR3_BG<1>"
$PN"DW62"114;
"DDR3_BA<0>"
$PN"EE52"115;
"DDR3_BA<1>"
$PN"EA54"116;
"DDR3_ALERT_N"
$PN"ED63"157;
"DDR3_ACT_N"
$PN"DW60"158;
%"TAP"
"6","(-5500,1325)","0","mstr_standard","I18";
;
HDL_TAP"TRUE"
BODY_TYPE"PLUMBING"
CDS_LIB"mstr_standard";
"B \NAC \NWC"12;
"S \NAC"
BN"5"20;
%"TAP"
"6","(-5500,1375)","0","mstr_standard","I19";
;
HDL_TAP"TRUE"
BODY_TYPE"PLUMBING"
CDS_LIB"mstr_standard";
"B \NAC \NWC"12;
"S \NAC"
BN"6"21;
%"TAP"
"6","(-5500,1425)","0","mstr_standard","I20";
;
HDL_TAP"TRUE"
BODY_TYPE"PLUMBING"
CDS_LIB"mstr_standard";
"B \NAC \NWC"12;
"S \NAC"
BN"7"22;
%"TAP"
"6","(-5500,1525)","0","mstr_standard","I21";
;
HDL_TAP"TRUE"
BODY_TYPE"PLUMBING"
CDS_LIB"mstr_standard";
"B \NAC \NWC"9;
"S \NAC"
BN"0"23;
%"TAP"
"6","(-5500,1575)","0","mstr_standard","I22";
;
HDL_TAP"TRUE"
BODY_TYPE"PLUMBING"
CDS_LIB"mstr_standard";
"B \NAC \NWC"9;
"S \NAC"
BN"1"24;
%"TAP"
"6","(-5500,1625)","0","mstr_standard","I23";
;
HDL_TAP"TRUE"
BODY_TYPE"PLUMBING"
CDS_LIB"mstr_standard";
"B \NAC \NWC"9;
"S \NAC"
BN"2"25;
%"TAP"
"6","(-5500,1675)","0","mstr_standard","I24";
;
HDL_TAP"TRUE"
BODY_TYPE"PLUMBING"
CDS_LIB"mstr_standard";
"B \NAC \NWC"9;
"S \NAC"
BN"3"26;
%"TAP"
"6","(-5500,1725)","0","mstr_standard","I25";
;
HDL_TAP"TRUE"
BODY_TYPE"PLUMBING"
CDS_LIB"mstr_standard";
"B \NAC \NWC"9;
"S \NAC"
BN"4"27;
%"TAP"
"6","(-5500,1775)","0","mstr_standard","I26";
;
HDL_TAP"TRUE"
BODY_TYPE"PLUMBING"
CDS_LIB"mstr_standard";
"B \NAC \NWC"9;
"S \NAC"
BN"5"13;
%"TAP"
"6","(-5500,1825)","0","mstr_standard","I27";
;
HDL_TAP"TRUE"
BODY_TYPE"PLUMBING"
CDS_LIB"mstr_standard";
"B \NAC \NWC"9;
"S \NAC"
BN"6"28;
%"TAP"
"6","(-5500,1925)","0","mstr_standard","I28";
;
HDL_TAP"TRUE"
BODY_TYPE"PLUMBING"
CDS_LIB"mstr_standard";
"B \NAC \NWC"9;
"S \NAC"
BN"8"30;
%"TAP"
"6","(-5500,1875)","0","mstr_standard","I29";
;
HDL_TAP"TRUE"
BODY_TYPE"PLUMBING"
CDS_LIB"mstr_standard";
"B \NAC \NWC"9;
"S \NAC"
BN"7"29;
%"TAP"
"6","(-5500,1975)","0","mstr_standard","I31";
;
HDL_TAP"TRUE"
BODY_TYPE"PLUMBING"
CDS_LIB"mstr_standard";
"B \NAC \NWC"9;
"S \NAC"
BN"9"31;
%"TAP"
"6","(-5500,2025)","0","mstr_standard","I32";
;
HDL_TAP"TRUE"
BODY_TYPE"PLUMBING"
CDS_LIB"mstr_standard";
"B \NAC \NWC"9;
"S \NAC"
BN"10"32;
%"TAP"
"6","(-5500,2075)","0","mstr_standard","I33";
;
HDL_TAP"TRUE"
BODY_TYPE"PLUMBING"
CDS_LIB"mstr_standard";
"B \NAC \NWC"9;
"S \NAC"
BN"11"41;
%"TAP"
"6","(-5500,2125)","0","mstr_standard","I34";
;
HDL_TAP"TRUE"
BODY_TYPE"PLUMBING"
CDS_LIB"mstr_standard";
"B \NAC \NWC"9;
"S \NAC"
BN"12"42;
%"TAP"
"6","(-5500,2175)","0","mstr_standard","I35";
;
HDL_TAP"TRUE"
BODY_TYPE"PLUMBING"
CDS_LIB"mstr_standard";
"B \NAC \NWC"9;
"S \NAC"
BN"13"43;
%"TAP"
"6","(-5500,2225)","0","mstr_standard","I36";
;
HDL_TAP"TRUE"
BODY_TYPE"PLUMBING"
CDS_LIB"mstr_standard";
"B \NAC \NWC"9;
"S \NAC"
BN"14"44;
%"TAP"
"6","(-5500,2275)","0","mstr_standard","I37";
;
HDL_TAP"TRUE"
BODY_TYPE"PLUMBING"
CDS_LIB"mstr_standard";
"B \NAC \NWC"9;
"S \NAC"
BN"15"45;
%"TAP"
"6","(-5500,2325)","0","mstr_standard","I38";
;
HDL_TAP"TRUE"
BODY_TYPE"PLUMBING"
CDS_LIB"mstr_standard";
"B \NAC \NWC"9;
"S \NAC"
BN"16"46;
%"TAP"
"6","(-5500,2375)","0","mstr_standard","I39";
;
HDL_TAP"TRUE"
BODY_TYPE"PLUMBING"
CDS_LIB"mstr_standard";
"B \NAC \NWC"9;
"S \NAC"
BN"17"47;
%"TAP"
"6","(-5500,2425)","0","mstr_standard","I40";
;
HDL_TAP"TRUE"
BODY_TYPE"PLUMBING"
CDS_LIB"mstr_standard";
"B \NAC \NWC"9;
"S \NAC"
BN"18"48;
%"TAP"
"6","(-5500,2475)","0","mstr_standard","I41";
;
HDL_TAP"TRUE"
BODY_TYPE"PLUMBING"
CDS_LIB"mstr_standard";
"B \NAC \NWC"9;
"S \NAC"
BN"19"49;
%"TAP"
"6","(-5500,2525)","0","mstr_standard","I42";
;
HDL_TAP"TRUE"
BODY_TYPE"PLUMBING"
CDS_LIB"mstr_standard";
"B \NAC \NWC"9;
"S \NAC"
BN"20"50;
%"TAP"
"6","(-5500,2575)","0","mstr_standard","I43";
;
HDL_TAP"TRUE"
BODY_TYPE"PLUMBING"
CDS_LIB"mstr_standard";
"B \NAC \NWC"9;
"S \NAC"
BN"21"51;
%"TAP"
"6","(-5500,2625)","0","mstr_standard","I44";
;
HDL_TAP"TRUE"
BODY_TYPE"PLUMBING"
CDS_LIB"mstr_standard";
"B \NAC \NWC"9;
"S \NAC"
BN"22"52;
%"TAP"
"6","(-5500,2675)","0","mstr_standard","I45";
;
HDL_TAP"TRUE"
BODY_TYPE"PLUMBING"
CDS_LIB"mstr_standard";
"B \NAC \NWC"9;
"S \NAC"
BN"23"53;
%"TAP"
"6","(-5500,2725)","0","mstr_standard","I46";
;
HDL_TAP"TRUE"
BODY_TYPE"PLUMBING"
CDS_LIB"mstr_standard";
"B \NAC \NWC"9;
"S \NAC"
BN"24"54;
%"TAP"
"6","(-5500,2825)","0","mstr_standard","I47";
;
HDL_TAP"TRUE"
BODY_TYPE"PLUMBING"
CDS_LIB"mstr_standard";
"B \NAC \NWC"9;
"S \NAC"
BN"26"56;
%"TAP"
"6","(-5500,2775)","0","mstr_standard","I48";
;
HDL_TAP"TRUE"
BODY_TYPE"PLUMBING"
CDS_LIB"mstr_standard";
"B \NAC \NWC"9;
"S \NAC"
BN"25"55;
%"TAP"
"6","(-5500,2875)","0","mstr_standard","I49";
;
HDL_TAP"TRUE"
BODY_TYPE"PLUMBING"
CDS_LIB"mstr_standard";
"B \NAC \NWC"9;
"S \NAC"
BN"27"57;
%"TAP"
"6","(-5500,625)","0","mstr_standard","I5";
;
HDL_TAP"TRUE"
BODY_TYPE"PLUMBING"
CDS_LIB"mstr_standard";
"B \NAC \NWC"10;
"S \NAC"
BN"0"37;
%"TAP"
"6","(-5500,2925)","0","mstr_standard","I50";
;
HDL_TAP"TRUE"
BODY_TYPE"PLUMBING"
CDS_LIB"mstr_standard";
"B \NAC \NWC"9;
"S \NAC"
BN"28"58;
%"TAP"
"6","(-5500,2975)","0","mstr_standard","I51";
;
HDL_TAP"TRUE"
BODY_TYPE"PLUMBING"
CDS_LIB"mstr_standard";
"B \NAC \NWC"9;
"S \NAC"
BN"29"59;
%"TAP"
"6","(-5500,3075)","0","mstr_standard","I52";
;
HDL_TAP"TRUE"
BODY_TYPE"PLUMBING"
CDS_LIB"mstr_standard";
"B \NAC \NWC"9;
"S \NAC"
BN"31"61;
%"TAP"
"6","(-5500,3025)","0","mstr_standard","I53";
;
HDL_TAP"TRUE"
BODY_TYPE"PLUMBING"
CDS_LIB"mstr_standard";
"B \NAC \NWC"9;
"S \NAC"
BN"30"60;
%"TAP"
"6","(-5500,3125)","0","mstr_standard","I54";
;
HDL_TAP"TRUE"
BODY_TYPE"PLUMBING"
CDS_LIB"mstr_standard";
"B \NAC \NWC"9;
"S \NAC"
BN"32"62;
%"TAP"
"6","(-5500,3175)","0","mstr_standard","I55";
;
HDL_TAP"TRUE"
BODY_TYPE"PLUMBING"
CDS_LIB"mstr_standard";
"B \NAC \NWC"9;
"S \NAC"
BN"33"63;
%"TAP"
"6","(-5500,3225)","0","mstr_standard","I56";
;
HDL_TAP"TRUE"
BODY_TYPE"PLUMBING"
CDS_LIB"mstr_standard";
"B \NAC \NWC"9;
"S \NAC"
BN"34"64;
%"TAP"
"6","(-5500,3325)","0","mstr_standard","I57";
;
HDL_TAP"TRUE"
BODY_TYPE"PLUMBING"
CDS_LIB"mstr_standard";
"B \NAC \NWC"9;
"S \NAC"
BN"36"66;
%"TAP"
"6","(-5500,3275)","0","mstr_standard","I58";
;
HDL_TAP"TRUE"
BODY_TYPE"PLUMBING"
CDS_LIB"mstr_standard";
"B \NAC \NWC"9;
"S \NAC"
BN"35"65;
%"TAP"
"6","(-5500,3375)","0","mstr_standard","I59";
;
HDL_TAP"TRUE"
BODY_TYPE"PLUMBING"
CDS_LIB"mstr_standard";
"B \NAC \NWC"9;
"S \NAC"
BN"37"67;
%"TAP"
"6","(-5500,675)","0","mstr_standard","I6";
;
HDL_TAP"TRUE"
BODY_TYPE"PLUMBING"
CDS_LIB"mstr_standard";
"B \NAC \NWC"10;
"S \NAC"
BN"1"38;
%"TAP"
"6","(-5500,3425)","0","mstr_standard","I60";
;
HDL_TAP"TRUE"
BODY_TYPE"PLUMBING"
CDS_LIB"mstr_standard";
"B \NAC \NWC"9;
"S \NAC"
BN"38"68;
%"TAP"
"6","(-5500,3475)","0","mstr_standard","I61";
;
HDL_TAP"TRUE"
BODY_TYPE"PLUMBING"
CDS_LIB"mstr_standard";
"B \NAC \NWC"9;
"S \NAC"
BN"39"69;
%"TAP"
"6","(-5500,3525)","0","mstr_standard","I62";
;
HDL_TAP"TRUE"
BODY_TYPE"PLUMBING"
CDS_LIB"mstr_standard";
"B \NAC \NWC"9;
"S \NAC"
BN"40"70;
%"TAP"
"6","(-5500,3575)","0","mstr_standard","I63";
;
HDL_TAP"TRUE"
BODY_TYPE"PLUMBING"
CDS_LIB"mstr_standard";
"B \NAC \NWC"9;
"S \NAC"
BN"41"71;
%"TAP"
"6","(-5500,3625)","0","mstr_standard","I64";
;
HDL_TAP"TRUE"
BODY_TYPE"PLUMBING"
CDS_LIB"mstr_standard";
"B \NAC \NWC"9;
"S \NAC"
BN"42"72;
%"TAP"
"6","(-5500,3675)","0","mstr_standard","I65";
;
HDL_TAP"TRUE"
BODY_TYPE"PLUMBING"
CDS_LIB"mstr_standard";
"B \NAC \NWC"9;
"S \NAC"
BN"43"73;
%"TAP"
"6","(-5500,3725)","0","mstr_standard","I66";
;
HDL_TAP"TRUE"
BODY_TYPE"PLUMBING"
CDS_LIB"mstr_standard";
"B \NAC \NWC"9;
"S \NAC"
BN"44"74;
%"TAP"
"6","(-5500,3775)","0","mstr_standard","I67";
;
HDL_TAP"TRUE"
BODY_TYPE"PLUMBING"
CDS_LIB"mstr_standard";
"B \NAC \NWC"9;
"S \NAC"
BN"45"75;
%"TAP"
"6","(-5500,3825)","0","mstr_standard","I68";
;
HDL_TAP"TRUE"
BODY_TYPE"PLUMBING"
CDS_LIB"mstr_standard";
"B \NAC \NWC"9;
"S \NAC"
BN"46"76;
%"TAP"
"6","(-5500,3875)","0","mstr_standard","I69";
;
HDL_TAP"TRUE"
BODY_TYPE"PLUMBING"
CDS_LIB"mstr_standard";
"B \NAC \NWC"9;
"S \NAC"
BN"47"77;
%"TAP"
"6","(-5500,775)","0","mstr_standard","I7";
;
HDL_TAP"TRUE"
BODY_TYPE"PLUMBING"
CDS_LIB"mstr_standard";
"B \NAC \NWC"10;
"S \NAC"
BN"3"40;
%"TAP"
"6","(-5500,3925)","0","mstr_standard","I70";
;
HDL_TAP"TRUE"
BODY_TYPE"PLUMBING"
CDS_LIB"mstr_standard";
"B \NAC \NWC"9;
"S \NAC"
BN"48"78;
%"TAP"
"6","(-5500,3975)","0","mstr_standard","I71";
;
HDL_TAP"TRUE"
BODY_TYPE"PLUMBING"
CDS_LIB"mstr_standard";
"B \NAC \NWC"9;
"S \NAC"
BN"49"79;
%"TAP"
"6","(-5500,4025)","0","mstr_standard","I73";
;
HDL_TAP"TRUE"
BODY_TYPE"PLUMBING"
CDS_LIB"mstr_standard";
"B \NAC \NWC"9;
"S \NAC"
BN"50"80;
%"TAP"
"6","(-5500,4075)","0","mstr_standard","I74";
;
HDL_TAP"TRUE"
BODY_TYPE"PLUMBING"
CDS_LIB"mstr_standard";
"B \NAC \NWC"9;
"S \NAC"
BN"51"81;
%"TAP"
"6","(-5500,4125)","0","mstr_standard","I75";
;
HDL_TAP"TRUE"
BODY_TYPE"PLUMBING"
CDS_LIB"mstr_standard";
"B \NAC \NWC"9;
"S \NAC"
BN"52"82;
%"TAP"
"6","(-5500,4175)","0","mstr_standard","I76";
;
HDL_TAP"TRUE"
BODY_TYPE"PLUMBING"
CDS_LIB"mstr_standard";
"B \NAC \NWC"9;
"S \NAC"
BN"53"83;
%"TAP"
"6","(-5500,4225)","0","mstr_standard","I77";
;
HDL_TAP"TRUE"
BODY_TYPE"PLUMBING"
CDS_LIB"mstr_standard";
"B \NAC \NWC"9;
"S \NAC"
BN"54"84;
%"TAP"
"6","(-5500,4275)","0","mstr_standard","I78";
;
HDL_TAP"TRUE"
BODY_TYPE"PLUMBING"
CDS_LIB"mstr_standard";
"B \NAC \NWC"9;
"S \NAC"
BN"55"85;
%"TAP"
"6","(-5500,4325)","0","mstr_standard","I79";
;
HDL_TAP"TRUE"
BODY_TYPE"PLUMBING"
CDS_LIB"mstr_standard";
"B \NAC \NWC"9;
"S \NAC"
BN"56"86;
%"TAP"
"6","(-5500,725)","0","mstr_standard","I8";
;
HDL_TAP"TRUE"
BODY_TYPE"PLUMBING"
CDS_LIB"mstr_standard";
"B \NAC \NWC"10;
"S \NAC"
BN"2"39;
%"TAP"
"6","(-5500,4375)","0","mstr_standard","I80";
;
HDL_TAP"TRUE"
BODY_TYPE"PLUMBING"
CDS_LIB"mstr_standard";
"B \NAC \NWC"9;
"S \NAC"
BN"57"87;
%"TAP"
"6","(-5500,4425)","0","mstr_standard","I81";
;
HDL_TAP"TRUE"
BODY_TYPE"PLUMBING"
CDS_LIB"mstr_standard";
"B \NAC \NWC"9;
"S \NAC"
BN"58"88;
%"TAP"
"6","(-5500,4475)","0","mstr_standard","I82";
;
HDL_TAP"TRUE"
BODY_TYPE"PLUMBING"
CDS_LIB"mstr_standard";
"B \NAC \NWC"9;
"S \NAC"
BN"59"89;
%"TAP"
"6","(-5500,4525)","0","mstr_standard","I83";
;
HDL_TAP"TRUE"
BODY_TYPE"PLUMBING"
CDS_LIB"mstr_standard";
"B \NAC \NWC"9;
"S \NAC"
BN"60"90;
%"TAP"
"6","(-5500,4575)","0","mstr_standard","I84";
;
HDL_TAP"TRUE"
BODY_TYPE"PLUMBING"
CDS_LIB"mstr_standard";
"B \NAC \NWC"9;
"S \NAC"
BN"61"91;
%"TAP"
"6","(-5500,4625)","0","mstr_standard","I85";
;
HDL_TAP"TRUE"
BODY_TYPE"PLUMBING"
CDS_LIB"mstr_standard";
"B \NAC \NWC"9;
"S \NAC"
BN"62"92;
%"TAP"
"6","(-5500,4675)","0","mstr_standard","I86";
;
HDL_TAP"TRUE"
BODY_TYPE"PLUMBING"
CDS_LIB"mstr_standard";
"B \NAC \NWC"9;
"S \NAC"
BN"63"93;
%"TAP"
"6","(-2775,725)","2","mstr_standard","I87";
;
HDL_TAP"TRUE"
BODY_TYPE"PLUMBING"
CDS_LIB"mstr_standard";
"B \NAC \NWC"4;
"S \NAC"
BN"0"115;
%"TAP"
"6","(-2775,775)","2","mstr_standard","I88";
;
HDL_TAP"TRUE"
BODY_TYPE"PLUMBING"
CDS_LIB"mstr_standard";
"B \NAC \NWC"4;
"S \NAC"
BN"1"116;
%"TAP"
"6","(-2775,875)","2","mstr_standard","I89";
;
HDL_TAP"TRUE"
BODY_TYPE"PLUMBING"
CDS_LIB"mstr_standard";
"B \NAC \NWC"5;
"S \NAC"
BN"1"114;
%"TAP"
"6","(-5500,825)","0","mstr_standard","I9";
;
HDL_TAP"TRUE"
BODY_TYPE"PLUMBING"
CDS_LIB"mstr_standard";
"B \NAC \NWC"11;
"S \NAC"
BN"0"33;
%"TAP"
"6","(-2775,825)","2","mstr_standard","I90";
;
HDL_TAP"TRUE"
BODY_TYPE"PLUMBING"
CDS_LIB"mstr_standard";
"B \NAC \NWC"5;
"S \NAC"
BN"0"113;
%"TAP"
"6","(-2775,1025)","2","mstr_standard","I91";
;
HDL_TAP"TRUE"
BODY_TYPE"PLUMBING"
CDS_LIB"mstr_standard";
"B \NAC \NWC"7;
"S \NAC"
BN"1"102;
%"TAP"
"6","(-2775,975)","2","mstr_standard","I92";
;
HDL_TAP"TRUE"
BODY_TYPE"PLUMBING"
CDS_LIB"mstr_standard";
"B \NAC \NWC"7;
"S \NAC"
BN"0"101;
%"TAP"
"6","(-2775,1075)","2","mstr_standard","I93";
;
HDL_TAP"TRUE"
BODY_TYPE"PLUMBING"
CDS_LIB"mstr_standard";
"B \NAC \NWC"7;
"S \NAC"
BN"2"103;
%"TAP"
"6","(-2775,1175)","2","mstr_standard","I94";
;
HDL_TAP"TRUE"
BODY_TYPE"PLUMBING"
CDS_LIB"mstr_standard";
"B \NAC \NWC"7;
"S \NAC"
BN"4"105;
%"TAP"
"6","(-2775,1125)","2","mstr_standard","I95";
;
HDL_TAP"TRUE"
BODY_TYPE"PLUMBING"
CDS_LIB"mstr_standard";
"B \NAC \NWC"7;
"S \NAC"
BN"3"104;
%"TAP"
"6","(-2775,1325)","2","mstr_standard","I96";
;
HDL_TAP"TRUE"
BODY_TYPE"PLUMBING"
CDS_LIB"mstr_standard";
"B \NAC \NWC"7;
"S \NAC"
BN"7"108;
%"TAP"
"6","(-2775,1225)","2","mstr_standard","I97";
;
HDL_TAP"TRUE"
BODY_TYPE"PLUMBING"
CDS_LIB"mstr_standard";
"B \NAC \NWC"7;
"S \NAC"
BN"5"106;
%"TAP"
"6","(-2775,1275)","2","mstr_standard","I98";
;
HDL_TAP"TRUE"
BODY_TYPE"PLUMBING"
CDS_LIB"mstr_standard";
"B \NAC \NWC"7;
"S \NAC"
BN"6"107;
%"TAP"
"6","(-2775,1425)","2","mstr_standard","I99";
;
HDL_TAP"TRUE"
BODY_TYPE"PLUMBING"
CDS_LIB"mstr_standard";
"B \NAC \NWC"8;
"S \NAC"
BN"0"94;
END.
